# T6G (Grand Teton) — schematic netlist excerpt (pin names and nets, part order shuffled) for the footprints in the layout excerpt that follows; sources: Cadence DE-HDL packaged netlist, KiCad conversion of 04192023_DAF0TMB3IC0_F0TG_MB_C_brd_V02_OCP.brd

R211  Q_RES  0 5% CHIP  pkg 0402LF  page 80 : A = SMB_2_PLD_3V3AUX_SDA_R1 ; B = SMB_2_PLD_3V3AUX_SDA_R2
PC204  Q_CAP  2.2UF 10V 10% X6S  pkg C0402  page 208 : A = PVDD11_S3_P0_VCC2 ; B = GND

(kicad_pcb
	(version 20260206)
	(generator "pcbnew")
	(generator_version "10.0")
	(general
		(thickness 1.6)
		(legacy_teardrops no)
	)
	(paper "A4")
	(title_block
		(title "04192023_DAF0TMB3IC0_F0TG_MB_C_brd_V02_OCP.brd")
		(comment 1 "Grand Teton / footprints 4831-4832 of 8354")
	)
	(layers
		(0 "F.Cu" signal "TOP")
		(4 "In1.Cu" signal "GND")
		(6 "In2.Cu" signal "IN1")
		(8 "In3.Cu" signal "GND1")
		(10 "In4.Cu" signal "IN2")
		(12 "In5.Cu" signal "GND2")
		(14 "In6.Cu" signal "IN3")
		(16 "In7.Cu" signal "GND3")
		(18 "In8.Cu" signal "VCC")
		(20 "In9.Cu" signal "VCC1")
		(22 "In10.Cu" signal "GND4")
		(24 "In11.Cu" signal "IN4")
		(26 "In12.Cu" signal "GND5")
		(28 "In13.Cu" signal "IN5")
		(30 "In14.Cu" signal "GND6")
		(32 "In15.Cu" signal "IN6")
		(34 "In16.Cu" signal "GND7")
		(2 "B.Cu" signal "BOTTOM")
		(9 "F.Adhes" user "F.Adhesive")
		(11 "B.Adhes" user "B.Adhesive")
		(13 "F.Paste" user "Package Geometry/Pastemask Top")
		(15 "B.Paste" user "Package Geometry/Pastemask Bottom")
		(5 "F.SilkS" user "Ref Des/Silkscreen Top")
		(7 "B.SilkS" user "Ref Des/Silkscreen Bottom")
		(1 "F.Mask" user "Board Geometry/Soldermask Top")
		(3 "B.Mask" user "Board Geometry/Soldermask Bottom")
		(17 "Dwgs.User" user "User.Drawings")
		(19 "Cmts.User" user "User.Comments")
		(21 "Eco1.User" user "User.Eco1")
		(23 "Eco2.User" user "User.Eco2")
		(25 "Edge.Cuts" user "Board Geometry/Outline")
		(27 "Margin" user)
		(31 "F.CrtYd" user "Package Geometry/Place Bound Top")
		(29 "B.CrtYd" user "Package Geometry/Place Bound Bottom")
		(35 "F.Fab" user "Ref Des/Assembly Top")
		(33 "B.Fab" user "Ref Des/Assembly Bottom")
	)
	(footprint ""
		(layer "F.Cu")
		(at 171.196 -118.328948)
		(property "Reference" "R211"
			(at 0 0 0)
			(layer "F.SilkS")
			(hide yes)
			(effects
				(font
					(size 1.27 1.27)
				)
			)
		)
		(property "Value" ""
			(at 0 0 0)
			(layer "F.Fab")
			(effects
				(font
					(size 1.27 1.27)
				)
			)
		)
		(duplicate_pad_numbers_are_jumpers no)
		(fp_line
			(start -0.7874 -0.4064)
			(end 0.7874 -0.4064)
			(stroke
				(width 0.1524)
				(type default)
			)
			(layer "F.SilkS")
		)
		(fp_line
			(start -0.7874 0.4064)
			(end -0.7874 -0.4064)
			(stroke
				(width 0.1524)
				(type default)
			)
			(layer "F.SilkS")
		)
		(fp_line
			(start 0.7874 -0.4064)
			(end 0.7874 0.4064)
			(stroke
				(width 0.1524)
				(type default)
			)
			(layer "F.SilkS")
		)
		(fp_line
			(start 0.7874 0.4064)
			(end -0.7874 0.4064)
			(stroke
				(width 0.1524)
				(type default)
			)
			(layer "F.SilkS")
		)
		(fp_line
			(start -0.67945 -0.305054)
			(end -0.12065 -0.305054)
			(stroke
				(width 0.1)
				(type default)
			)
			(layer "F.Fab")
		)
		(fp_line
			(start -0.67945 0.3048)
			(end -0.67945 -0.305054)
			(stroke
				(width 0.1)
				(type default)
			)
			(layer "F.Fab")
		)
		(fp_line
			(start -0.12065 -0.305054)
			(end -0.12065 -0.2794)
			(stroke
				(width 0.1)
				(type default)
			)
			(layer "F.Fab")
		)
		(fp_line
			(start -0.12065 -0.2794)
			(end 0.12065 -0.2794)
			(stroke
				(width 0.1)
				(type default)
			)
			(layer "F.Fab")
		)
		(fp_line
			(start -0.12065 0.2794)
			(end -0.12065 0.3048)
			(stroke
				(width 0.1)
				(type default)
			)
			(layer "F.Fab")
		)
		(fp_line
			(start -0.12065 0.3048)
			(end -0.67945 0.3048)
			(stroke
				(width 0.1)
				(type default)
			)
			(layer "F.Fab")
		)
		(fp_line
			(start 0.120396 0.2794)
			(end -0.12065 0.2794)
			(stroke
				(width 0.1)
				(type default)
			)
			(layer "F.Fab")
		)
		(fp_line
			(start 0.120396 0.3048)
			(end 0.120396 0.2794)
			(stroke
				(width 0.1)
				(type default)
			)
			(layer "F.Fab")
		)
		(fp_line
			(start 0.12065 -0.3048)
			(end 0.67945 -0.3048)
			(stroke
				(width 0.1)
				(type default)
			)
			(layer "F.Fab")
		)
		(fp_line
			(start 0.12065 -0.2794)
			(end 0.12065 -0.3048)
			(stroke
				(width 0.1)
				(type default)
			)
			(layer "F.Fab")
		)
		(fp_line
			(start 0.67945 -0.3048)
			(end 0.67945 0.3048)
			(stroke
				(width 0.1)
				(type default)
			)
			(layer "F.Fab")
		)
		(fp_line
			(start 0.67945 0.3048)
			(end 0.120396 0.3048)
			(stroke
				(width 0.1)
				(type default)
			)
			(layer "F.Fab")
		)
		(pad "1" smd circle
			(at -0.40005 0)
			(size 0 0)
			(layers "F.Cu" "F.Mask" "F.Paste")
			(net "SMB_2_PLD_3V3AUX_SDA_R1")
		)
		(pad "2" smd circle
			(at 0.40005 0)
			(size 0 0)
			(layers "F.Cu" "F.Mask" "F.Paste")
			(net "SMB_2_PLD_3V3AUX_SDA_R2")
		)
	)
	(footprint ""
		(layer "F.Cu")
		(at 428.287688 -353.80549 90)
		(property "Reference" "PC204"
			(at 0 0 90)
			(layer "F.SilkS")
			(hide yes)
			(effects
				(font
					(size 1.27 1.27)
				)
			)
		)
		(property "Value" ""
			(at 0 0 90)
			(layer "F.Fab")
			(effects
				(font
					(size 1.27 1.27)
				)
			)
		)
		(duplicate_pad_numbers_are_jumpers no)
		(fp_line
			(start 0.7874 -0.4064)
			(end 0.7874 0.4064)
			(stroke
				(width 0.1524)
				(type default)
			)
			(layer "F.SilkS")
		)
		(fp_line
			(start -0.7874 -0.4064)
			(end 0.7874 -0.4064)
			(stroke
				(width 0.1524)
				(type default)
			)
			(layer "F.SilkS")
		)
		(fp_line
			(start 0.7874 0.4064)
			(end 0.44831 0.4064)
			(stroke
				(width 0.1524)
				(type default)
			)
			(layer "F.SilkS")
		)
		(fp_line
			(start -0.23749 0.4064)
			(end -0.7874 0.4064)
			(stroke
				(width 0.1524)
				(type default)
			)
			(layer "F.SilkS")
		)
		(fp_line
			(start -0.7874 0.4064)
			(end -0.7874 -0.4064)
			(stroke
				(width 0.1524)
				(type default)
			)
			(layer "F.SilkS")
		)
		(fp_line
			(start -0.12065 -0.305054)
			(end -0.12065 -0.2794)
			(stroke
				(width 0.1)
				(type default)
			)
			(layer "F.Fab")
		)
		(fp_line
			(start -0.67945 -0.305054)
			(end -0.12065 -0.305054)
			(stroke
				(width 0.1)
				(type default)
			)
			(layer "F.Fab")
		)
		(fp_line
			(start 0.67945 -0.3048)
			(end 0.67945 0.3048)
			(stroke
				(width 0.1)
				(type default)
			)
			(layer "F.Fab")
		)
		(fp_line
			(start 0.12065 -0.3048)
			(end 0.67945 -0.3048)
			(stroke
				(width 0.1)
				(type default)
			)
			(layer "F.Fab")
		)
		(fp_line
			(start 0.12065 -0.2794)
			(end 0.12065 -0.3048)
			(stroke
				(width 0.1)
				(type default)
			)
			(layer "F.Fab")
		)
		(fp_line
			(start -0.12065 -0.2794)
			(end 0.12065 -0.2794)
			(stroke
				(width 0.1)
				(type default)
			)
			(layer "F.Fab")
		)
		(fp_line
			(start 0.120396 0.2794)
			(end -0.12065 0.2794)
			(stroke
				(width 0.1)
				(type default)
			)
			(layer "F.Fab")
		)
		(fp_line
			(start -0.12065 0.2794)
			(end -0.12065 0.3048)
			(stroke
				(width 0.1)
				(type default)
			)
			(layer "F.Fab")
		)
		(fp_line
			(start 0.67945 0.3048)
			(end 0.120396 0.3048)
			(stroke
				(width 0.1)
				(type default)
			)
			(layer "F.Fab")
		)
		(fp_line
			(start 0.120396 0.3048)
			(end 0.120396 0.2794)
			(stroke
				(width 0.1)
				(type default)
			)
			(layer "F.Fab")
		)
		(fp_line
			(start -0.12065 0.3048)
			(end -0.67945 0.3048)
			(stroke
				(width 0.1)
				(type default)
			)
			(layer "F.Fab")
		)
		(fp_line
			(start -0.67945 0.3048)
			(end -0.67945 -0.305054)
			(stroke
				(width 0.1)
				(type default)
			)
			(layer "F.Fab")
		)
		(pad "1" smd circle
			(at -0.40005 0 90)
			(size 0 0)
			(layers "F.Cu" "F.Mask" "F.Paste")
			(net "PVDD11_S3_P0_VCC2")
		)
		(pad "2" smd circle
			(at 0.40005 0 90)
			(size 0 0)
			(layers "F.Cu" "F.Mask" "F.Paste")
			(net "GND")
		)
	)
)
